# BASEBOARD_FAB2 (Tioga Pass) — schematic netlist excerpt (pin names and nets, part order shuffled) for the footprints in the layout excerpt that follows; sources: Cadence DE-HDL packaged netlist, KiCad conversion of Wiwynn_Tioga_Pass_MB.brd

R7G23  RES  10.0K 1% CHIP  pkg 0402  page 189 : A = P3V3_STBY ; B = JTAG_TDI_R
C4B13  CAPP  470UF 16V 20% ALUM  pkg 4040LF  page 195 : A = P12V_STBY ; B = GND

(kicad_pcb
	(version 20260206)
	(generator "pcbnew")
	(generator_version "10.0")
	(general
		(thickness 1.6)
		(legacy_teardrops no)
	)
	(paper "A4")
	(title_block
		(title "Wiwynn_Tioga_Pass_MB.brd")
		(comment 1 "Tioga Pass / footprints 1924-1925 of 4770")
	)
	(layers
		(0 "F.Cu" signal "TOP")
		(4 "In1.Cu" signal "L2GND")
		(6 "In2.Cu" signal "L3")
		(8 "In3.Cu" signal "L4GND")
		(10 "In4.Cu" signal "L5")
		(12 "In5.Cu" signal "L6GND")
		(14 "In6.Cu" signal "L7VCC")
		(16 "In7.Cu" signal "L8VCC")
		(18 "In8.Cu" signal "L9GND")
		(20 "In9.Cu" signal "L10")
		(22 "In10.Cu" signal "L11GND")
		(24 "In11.Cu" signal "L12")
		(26 "In12.Cu" signal "L13GND")
		(2 "B.Cu" signal "BOTTOM")
		(9 "F.Adhes" user "F.Adhesive")
		(11 "B.Adhes" user "B.Adhesive")
		(13 "F.Paste" user "Package Geometry/Pastemask Top")
		(15 "B.Paste" user "Package Geometry/Pastemask Bottom")
		(5 "F.SilkS" user "Ref Des/Silkscreen Top")
		(7 "B.SilkS" user "Ref Des/Silkscreen Bottom")
		(1 "F.Mask" user "Board Geometry/Soldermask Top")
		(3 "B.Mask" user "Board Geometry/Soldermask Bottom")
		(17 "Dwgs.User" user "User.Drawings")
		(19 "Cmts.User" user "User.Comments")
		(21 "Eco1.User" user "User.Eco1")
		(23 "Eco2.User" user "User.Eco2")
		(25 "Edge.Cuts" user "Board Geometry/Outline")
		(27 "Margin" user)
		(31 "F.CrtYd" user "Package Geometry/Place Bound Top")
		(29 "B.CrtYd" user "Package Geometry/Place Bound Bottom")
		(35 "F.Fab" user "Ref Des/Assembly Top")
		(33 "B.Fab" user "Ref Des/Assembly Bottom")
	)
	(footprint ""
		(layer "F.Cu")
		(at 387.35 1.651 90)
		(property "Reference" "R7G23"
			(at 0 0 90)
			(layer "F.SilkS")
			(hide yes)
			(effects
				(font
					(size 1.27 1.27)
				)
			)
		)
		(property "Value" ""
			(at 0 0 90)
			(layer "F.Fab")
			(effects
				(font
					(size 1.27 1.27)
				)
			)
		)
		(duplicate_pad_numbers_are_jumpers no)
		(fp_poly
			(pts
				(xy -0.2794 -0.1016) (xy 0.2794 -0.1016) (xy 0.2794 0.9906) (xy -0.2794 0.9906)
			)
			(stroke
				(width 0)
				(type default)
			)
			(fill no)
			(layer "F.CrtYd")
		)
		(fp_line
			(start 0.2794 -0.1016)
			(end -0.2794 -0.1016)
			(stroke
				(width 0.1)
				(type default)
			)
			(layer "F.Fab")
		)
		(fp_line
			(start -0.2794 -0.1016)
			(end -0.2794 0.9906)
			(stroke
				(width 0.1)
				(type default)
			)
			(layer "F.Fab")
		)
		(fp_line
			(start 0.2794 0.9906)
			(end 0.2794 -0.1016)
			(stroke
				(width 0.1)
				(type default)
			)
			(layer "F.Fab")
		)
		(fp_line
			(start -0.2794 0.9906)
			(end 0.2794 0.9906)
			(stroke
				(width 0.1)
				(type default)
			)
			(layer "F.Fab")
		)
		(pad "1" smd rect
			(at 0 0 90)
			(size 0.508 0.508)
			(layers "F.Cu" "F.Mask" "F.Paste")
			(net "P3V3_STBY")
		)
		(pad "2" smd rect
			(at 0 0.889 90)
			(size 0.508 0.508)
			(layers "F.Cu" "F.Mask" "F.Paste")
			(net "JTAG_TDI_R")
		)
		(zone
			(layer "F.Cu")
			(hatch none 0.5)
			(connect_pads
				(clearance 0)
			)
			(min_thickness 0.25)
			(keepout
				(tracks allowed)
				(vias not_allowed)
				(pads allowed)
				(copperpour not_allowed)
				(footprints allowed)
			)
			(placement
				(enabled no)
				(sheetname "")
			)
			(fill
				(thermal_gap 0.5)
				(thermal_bridge_width 0.5)
				(island_removal_mode 0)
			)
			(polygon
				(pts
					(xy 387.604 1.905) (xy 387.604 1.397) (xy 387.985 1.397) (xy 387.985 1.905)
				)
			)
		)
		(zone
			(layer "F.Cu")
			(hatch none 0.5)
			(connect_pads
				(clearance 0)
			)
			(min_thickness 0.25)
			(keepout
				(tracks not_allowed)
				(vias allowed)
				(pads allowed)
				(copperpour not_allowed)
				(footprints allowed)
			)
			(placement
				(enabled no)
				(sheetname "")
			)
			(fill
				(thermal_gap 0.5)
				(thermal_bridge_width 0.5)
				(island_removal_mode 0)
			)
			(polygon
				(pts
					(xy 387.985 1.905) (xy 387.985 1.397) (xy 387.604 1.397) (xy 387.604 1.905)
				)
			)
		)
	)
	(footprint ""
		(layer "F.Cu")
		(at 198.877936 -122.301)
		(property "Reference" "C4B13"
			(at 3.2512 10.18667 0)
			(unlocked yes)
			(layer "F.SilkS")
			(effects
				(font
					(size 0.7874 0.5842)
					(thickness 0.1524)
				)
			)
		)
		(property "Value" ""
			(at 0 0 0)
			(layer "F.Fab")
			(effects
				(font
					(size 1.27 1.27)
				)
			)
		)
		(duplicate_pad_numbers_are_jumpers no)
		(fp_line
			(start -5.1435 -0.127)
			(end -4.3815 -1.016)
			(stroke
				(width 0.1524)
				(type default)
			)
			(layer "F.SilkS")
		)
		(fp_line
			(start -5.1435 9.271)
			(end -5.1435 -0.127)
			(stroke
				(width 0.1524)
				(type default)
			)
			(layer "F.SilkS")
		)
		(fp_line
			(start -4.3815 -1.016)
			(end -1.8415 -1.016)
			(stroke
				(width 0.1524)
				(type default)
			)
			(layer "F.SilkS")
		)
		(fp_line
			(start -1.8415 -2.0955)
			(end -1.8415 2.0955)
			(stroke
				(width 0.1524)
				(type default)
			)
			(layer "F.SilkS")
		)
		(fp_line
			(start -1.8415 2.0955)
			(end -1.4097 2.0955)
			(stroke
				(width 0.1524)
				(type default)
			)
			(layer "F.SilkS")
		)
		(fp_line
			(start -1.4097 -2.0955)
			(end -1.8415 -2.0955)
			(stroke
				(width 0.1524)
				(type default)
			)
			(layer "F.SilkS")
		)
		(fp_line
			(start -1.4097 9.271)
			(end -5.1435 9.271)
			(stroke
				(width 0.1524)
				(type default)
			)
			(layer "F.SilkS")
		)
		(fp_line
			(start 1.4097 -2.0955)
			(end 1.8415 -2.0955)
			(stroke
				(width 0.1524)
				(type default)
			)
			(layer "F.SilkS")
		)
		(fp_line
			(start 1.8415 -2.0955)
			(end 1.8415 2.0955)
			(stroke
				(width 0.1524)
				(type default)
			)
			(layer "F.SilkS")
		)
		(fp_line
			(start 1.8415 -1.016)
			(end 4.3815 -1.016)
			(stroke
				(width 0.1524)
				(type default)
			)
			(layer "F.SilkS")
		)
		(fp_line
			(start 1.8415 2.0955)
			(end 1.4097 2.0955)
			(stroke
				(width 0.1524)
				(type default)
			)
			(layer "F.SilkS")
		)
		(fp_line
			(start 4.3815 -1.016)
			(end 5.1435 -0.127)
			(stroke
				(width 0.1524)
				(type default)
			)
			(layer "F.SilkS")
		)
		(fp_line
			(start 5.1435 -0.127)
			(end 5.1435 9.271)
			(stroke
				(width 0.1524)
				(type default)
			)
			(layer "F.SilkS")
		)
		(fp_line
			(start 5.1435 9.271)
			(end 1.4097 9.271)
			(stroke
				(width 0.1524)
				(type default)
			)
			(layer "F.SilkS")
		)
		(fp_poly
			(pts
				(xy -5.14604 -0.12954) (xy -4.38404 -1.01346) (xy 4.37896 -1.016) (xy 5.1435 -0.12954) (xy 5.14096 9.271)
				(xy -5.14604 9.27354)
			)
			(stroke
				(width 0)
				(type default)
			)
			(fill no)
			(layer "F.CrtYd")
		)
		(fp_line
			(start -5.1435 -0.127)
			(end -4.3815 -1.016)
			(stroke
				(width 0.1)
				(type default)
			)
			(layer "F.Fab")
		)
		(fp_line
			(start -5.1435 9.271)
			(end -5.1435 -0.127)
			(stroke
				(width 0.1)
				(type default)
			)
			(layer "F.Fab")
		)
		(fp_line
			(start -4.3815 -1.016)
			(end 4.3815 -1.016)
			(stroke
				(width 0.1)
				(type default)
			)
			(layer "F.Fab")
		)
		(fp_line
			(start 4.3815 -1.016)
			(end 5.1435 -0.127)
			(stroke
				(width 0.1)
				(type default)
			)
			(layer "F.Fab")
		)
		(fp_line
			(start 5.1435 -0.127)
			(end 5.1435 9.271)
			(stroke
				(width 0.1)
				(type default)
			)
			(layer "F.Fab")
		)
		(fp_line
			(start 5.1435 9.271)
			(end -5.1435 9.271)
			(stroke
				(width 0.1)
				(type default)
			)
			(layer "F.Fab")
		)
		(fp_circle
			(center 0 4.1275)
			(end 4.9911 4.1275)
			(stroke
				(width 0.1)
				(type default)
			)
			(fill no)
			(layer "F.Fab")
		)
		(pad "1" smd rect
			(at 0 0)
			(size 1.905 4.191)
			(layers "F.Cu" "F.Mask" "F.Paste")
			(net "P12V_STBY")
		)
		(pad "2" smd rect
			(at 0 8.255)
			(size 1.905 4.191)
			(layers "F.Cu" "F.Mask" "F.Paste")
			(net "GND")
		)
		(zone
			(layer "F.Cu")
			(hatch none 0.5)
			(connect_pads
				(clearance 0)
			)
			(min_thickness 0.25)
			(keepout
				(tracks allowed)
				(vias not_allowed)
				(pads allowed)
				(copperpour not_allowed)
				(footprints allowed)
			)
			(placement
				(enabled no)
				(sheetname "")
			)
			(fill
				(thermal_gap 0.5)
				(thermal_bridge_width 0.5)
				(island_removal_mode 0)
			)
			(polygon
				(pts
					(xy 193.734436 -113.03) (xy 204.021436 -113.03) (xy 204.021436 -122.428) (xy 203.259436 -123.317)
					(xy 194.496436 -123.317) (xy 193.734436 -122.428)
				)
			)
		)
	)
)
